# S9S_MB_2U (Grand Teton) — schematic netlist excerpt (pin names and nets, part order shuffled) for the footprints in the layout excerpt that follows; sources: Cadence DE-HDL packaged netlist, KiCad conversion of 03242023_DA0F0TMBIJ0_F0T_Motherboard_J_brd_V01_OCP.brd

R2397  Q_RES  0 5% CHIP  pkg 0402LF  page 274 : A = PWRGD_PVCCFA_EHV_CPU0 ; B = PWRGD_PVCCFA_EHV_CPU0_R
C1835  Q_CAP  0.1UF 25V 10% X7R  pkg 0402  page 159 : A = P3V3_OCP_V3_2 ; B = GND
C70  Q_CAP  10UF 16V 10% X6S  pkg C0805  page 104 : A = P12V_S3_AUX_CPU1_NVDIMM ; B = GND

(kicad_pcb
	(version 20260206)
	(generator "pcbnew")
	(generator_version "10.0")
	(general
		(thickness 1.6)
		(legacy_teardrops no)
	)
	(paper "A4")
	(title_block
		(title "03242023_DA0F0TMBIJ0_F0T_Motherboard_J_brd_V01_OCP.brd")
		(comment 1 "Grand Teton / footprints 4577-4579 of 6105")
	)
	(layers
		(0 "F.Cu" signal "TOP")
		(4 "In1.Cu" signal "GND")
		(6 "In2.Cu" signal "IN1")
		(8 "In3.Cu" signal "GND1")
		(10 "In4.Cu" signal "IN2")
		(12 "In5.Cu" signal "GND2")
		(14 "In6.Cu" signal "IN3")
		(16 "In7.Cu" signal "GND3")
		(18 "In8.Cu" signal "VCC")
		(20 "In9.Cu" signal "VCC1")
		(22 "In10.Cu" signal "GND4")
		(24 "In11.Cu" signal "IN4")
		(26 "In12.Cu" signal "GND5")
		(28 "In13.Cu" signal "IN5")
		(30 "In14.Cu" signal "GND6")
		(32 "In15.Cu" signal "IN6")
		(34 "In16.Cu" signal "GND7")
		(2 "B.Cu" signal "BOTTOM")
		(9 "F.Adhes" user "F.Adhesive")
		(11 "B.Adhes" user "B.Adhesive")
		(13 "F.Paste" user "Package Geometry/Pastemask Top")
		(15 "B.Paste" user "Package Geometry/Pastemask Bottom")
		(5 "F.SilkS" user "Ref Des/Silkscreen Top")
		(7 "B.SilkS" user "Ref Des/Silkscreen Bottom")
		(1 "F.Mask" user "Board Geometry/Soldermask Top")
		(3 "B.Mask" user "Board Geometry/Soldermask Bottom")
		(17 "Dwgs.User" user "User.Drawings")
		(19 "Cmts.User" user "User.Comments")
		(21 "Eco1.User" user "User.Eco1")
		(23 "Eco2.User" user "User.Eco2")
		(25 "Edge.Cuts" user "Board Geometry/Outline")
		(27 "Margin" user)
		(31 "F.CrtYd" user "Package Geometry/Place Bound Top")
		(29 "B.CrtYd" user "Package Geometry/Place Bound Bottom")
		(35 "F.Fab" user "Ref Des/Assembly Top")
		(33 "B.Fab" user "Ref Des/Assembly Bottom")
	)
	(footprint ""
		(layer "B.Cu")
		(at 430.600104 -138.558778)
		(property "Reference" "R2397"
			(at 0 0 0)
			(layer "B.SilkS")
			(hide yes)
			(effects
				(font
					(size 1.27 1.27)
				)
				(justify mirror)
			)
		)
		(property "Value" ""
			(at 0 0 0)
			(layer "B.Fab")
			(effects
				(font
					(size 1.27 1.27)
				)
				(justify mirror)
			)
		)
		(duplicate_pad_numbers_are_jumpers no)
		(fp_line
			(start -0.7874 -0.4064)
			(end -0.7874 0.4064)
			(stroke
				(width 0.1524)
				(type default)
			)
			(layer "B.SilkS")
		)
		(fp_line
			(start -0.7874 0.4064)
			(end 0.7874 0.4064)
			(stroke
				(width 0.1524)
				(type default)
			)
			(layer "B.SilkS")
		)
		(fp_line
			(start 0.7874 -0.4064)
			(end -0.7874 -0.4064)
			(stroke
				(width 0.1524)
				(type default)
			)
			(layer "B.SilkS")
		)
		(fp_line
			(start 0.7874 0.4064)
			(end 0.7874 -0.4064)
			(stroke
				(width 0.1524)
				(type default)
			)
			(layer "B.SilkS")
		)
		(fp_line
			(start -0.67945 -0.3048)
			(end -0.67945 0.3048)
			(stroke
				(width 0.1)
				(type default)
			)
			(layer "B.Fab")
		)
		(fp_line
			(start -0.67945 0.3048)
			(end -0.120396 0.3048)
			(stroke
				(width 0.1)
				(type default)
			)
			(layer "B.Fab")
		)
		(fp_line
			(start -0.12065 -0.3048)
			(end -0.67945 -0.3048)
			(stroke
				(width 0.1)
				(type default)
			)
			(layer "B.Fab")
		)
		(fp_line
			(start -0.12065 -0.2794)
			(end -0.12065 -0.3048)
			(stroke
				(width 0.1)
				(type default)
			)
			(layer "B.Fab")
		)
		(fp_line
			(start -0.120396 0.2794)
			(end 0.12065 0.2794)
			(stroke
				(width 0.1)
				(type default)
			)
			(layer "B.Fab")
		)
		(fp_line
			(start -0.120396 0.3048)
			(end -0.120396 0.2794)
			(stroke
				(width 0.1)
				(type default)
			)
			(layer "B.Fab")
		)
		(fp_line
			(start 0.12065 -0.305054)
			(end 0.12065 -0.2794)
			(stroke
				(width 0.1)
				(type default)
			)
			(layer "B.Fab")
		)
		(fp_line
			(start 0.12065 -0.2794)
			(end -0.12065 -0.2794)
			(stroke
				(width 0.1)
				(type default)
			)
			(layer "B.Fab")
		)
		(fp_line
			(start 0.12065 0.2794)
			(end 0.12065 0.3048)
			(stroke
				(width 0.1)
				(type default)
			)
			(layer "B.Fab")
		)
		(fp_line
			(start 0.12065 0.3048)
			(end 0.67945 0.3048)
			(stroke
				(width 0.1)
				(type default)
			)
			(layer "B.Fab")
		)
		(fp_line
			(start 0.67945 -0.305054)
			(end 0.12065 -0.305054)
			(stroke
				(width 0.1)
				(type default)
			)
			(layer "B.Fab")
		)
		(fp_line
			(start 0.67945 0.3048)
			(end 0.67945 -0.305054)
			(stroke
				(width 0.1)
				(type default)
			)
			(layer "B.Fab")
		)
		(pad "1" smd circle
			(at 0.40005 0 180)
			(size 0 0)
			(layers "B.Cu" "B.Mask" "B.Paste")
			(net "PWRGD_PVCCFA_EHV_CPU0")
		)
		(pad "2" smd circle
			(at -0.40005 0 180)
			(size 0 0)
			(layers "B.Cu" "B.Mask" "B.Paste")
			(net "PWRGD_PVCCFA_EHV_CPU0_R")
		)
	)
	(footprint ""
		(layer "B.Cu")
		(at 64.546988 -8.98398 90)
		(property "Reference" "C1835"
			(at 0 0 90)
			(layer "B.SilkS")
			(hide yes)
			(effects
				(font
					(size 1.27 1.27)
				)
				(justify mirror)
			)
		)
		(property "Value" ""
			(at 0 0 90)
			(layer "B.Fab")
			(effects
				(font
					(size 1.27 1.27)
				)
				(justify mirror)
			)
		)
		(duplicate_pad_numbers_are_jumpers no)
		(fp_line
			(start 0.7874 -0.4064)
			(end -0.7874 -0.4064)
			(stroke
				(width 0.1524)
				(type default)
			)
			(layer "B.SilkS")
		)
		(fp_line
			(start -0.7874 -0.4064)
			(end -0.7874 0.4064)
			(stroke
				(width 0.1524)
				(type default)
			)
			(layer "B.SilkS")
		)
		(fp_line
			(start 0.7874 0.4064)
			(end 0.7874 -0.4064)
			(stroke
				(width 0.1524)
				(type default)
			)
			(layer "B.SilkS")
		)
		(fp_line
			(start -0.7874 0.4064)
			(end 0.7874 0.4064)
			(stroke
				(width 0.1524)
				(type default)
			)
			(layer "B.SilkS")
		)
		(fp_line
			(start 0.67945 -0.305054)
			(end 0.12065 -0.305054)
			(stroke
				(width 0.1)
				(type default)
			)
			(layer "B.Fab")
		)
		(fp_line
			(start 0.12065 -0.305054)
			(end 0.12065 -0.2794)
			(stroke
				(width 0.1)
				(type default)
			)
			(layer "B.Fab")
		)
		(fp_line
			(start -0.12065 -0.3048)
			(end -0.67945 -0.3048)
			(stroke
				(width 0.1)
				(type default)
			)
			(layer "B.Fab")
		)
		(fp_line
			(start -0.67945 -0.3048)
			(end -0.67945 0.3048)
			(stroke
				(width 0.1)
				(type default)
			)
			(layer "B.Fab")
		)
		(fp_line
			(start 0.12065 -0.2794)
			(end -0.12065 -0.2794)
			(stroke
				(width 0.1)
				(type default)
			)
			(layer "B.Fab")
		)
		(fp_line
			(start -0.12065 -0.2794)
			(end -0.12065 -0.3048)
			(stroke
				(width 0.1)
				(type default)
			)
			(layer "B.Fab")
		)
		(fp_line
			(start 0.12065 0.2794)
			(end 0.12065 0.3048)
			(stroke
				(width 0.1)
				(type default)
			)
			(layer "B.Fab")
		)
		(fp_line
			(start -0.120396 0.2794)
			(end 0.12065 0.2794)
			(stroke
				(width 0.1)
				(type default)
			)
			(layer "B.Fab")
		)
		(fp_line
			(start 0.67945 0.3048)
			(end 0.67945 -0.305054)
			(stroke
				(width 0.1)
				(type default)
			)
			(layer "B.Fab")
		)
		(fp_line
			(start 0.12065 0.3048)
			(end 0.67945 0.3048)
			(stroke
				(width 0.1)
				(type default)
			)
			(layer "B.Fab")
		)
		(fp_line
			(start -0.120396 0.3048)
			(end -0.120396 0.2794)
			(stroke
				(width 0.1)
				(type default)
			)
			(layer "B.Fab")
		)
		(fp_line
			(start -0.67945 0.3048)
			(end -0.120396 0.3048)
			(stroke
				(width 0.1)
				(type default)
			)
			(layer "B.Fab")
		)
		(pad "1" smd circle
			(at 0.40005 0 270)
			(size 0 0)
			(layers "B.Cu" "B.Mask" "B.Paste")
			(net "P3V3_OCP_V3_2")
		)
		(pad "2" smd circle
			(at -0.40005 0 270)
			(size 0 0)
			(layers "B.Cu" "B.Mask" "B.Paste")
			(net "GND")
		)
	)
	(footprint ""
		(layer "B.Cu")
		(at 8.153146 -321.554856 -90)
		(property "Reference" "C70"
			(at 0 0 90)
			(layer "B.SilkS")
			(hide yes)
			(effects
				(font
					(size 1.27 1.27)
				)
				(justify mirror)
			)
		)
		(property "Value" ""
			(at 0 0 90)
			(layer "B.Fab")
			(effects
				(font
					(size 1.27 1.27)
				)
				(justify mirror)
			)
		)
		(duplicate_pad_numbers_are_jumpers no)
		(fp_line
			(start -1.524 0.762)
			(end 1.524 0.762)
			(stroke
				(width 0.1524)
				(type default)
			)
			(layer "B.SilkS")
		)
		(fp_line
			(start 1.524 0.762)
			(end 1.524 -0.762)
			(stroke
				(width 0.1524)
				(type default)
			)
			(layer "B.SilkS")
		)
		(fp_line
			(start -1.524 -0.762)
			(end -1.524 0.762)
			(stroke
				(width 0.1524)
				(type default)
			)
			(layer "B.SilkS")
		)
		(fp_line
			(start 1.524 -0.762)
			(end -1.524 -0.762)
			(stroke
				(width 0.1524)
				(type default)
			)
			(layer "B.SilkS")
		)
		(fp_line
			(start -1.1049 0.724916)
			(end -1.1049 -0.724916)
			(stroke
				(width 0.1)
				(type default)
			)
			(layer "B.Fab")
		)
		(fp_line
			(start 1.1049 0.724916)
			(end -1.1049 0.724916)
			(stroke
				(width 0.1)
				(type default)
			)
			(layer "B.Fab")
		)
		(fp_line
			(start -1.1049 -0.724916)
			(end 1.1049 -0.724916)
			(stroke
				(width 0.1)
				(type default)
			)
			(layer "B.Fab")
		)
		(fp_line
			(start 1.1049 -0.724916)
			(end 1.1049 0.724916)
			(stroke
				(width 0.1)
				(type default)
			)
			(layer "B.Fab")
		)
		(pad "1" smd rect
			(at 0.889 0 270)
			(size 1.016 1.27)
			(layers "B.Cu" "B.Mask" "B.Paste")
			(net "P12V_S3_AUX_CPU1_NVDIMM")
		)
		(pad "2" smd rect
			(at -0.889 0 270)
			(size 1.016 1.27)
			(layers "B.Cu" "B.Mask" "B.Paste")
			(net "GND")
		)
	)
)
